# T6G (Grand Teton) — schematic netlist excerpt (pin names and nets, part order shuffled) for the footprints in the layout excerpt that follows; sources: Cadence DE-HDL packaged netlist, KiCad conversion of 04192023_DAF0TMB3IC0_F0TG_MB_C_brd_V02_OCP.brd

C231  Q_CAP  0.001UF 50V 10% EMPTY  pkg C0402  page 54 : A = JTAG_CPU1_TDI ; B = GND

Q80  MOSFET_NCH_DUAL  PJT138K IC  pkg SOT363XD  page 255
  S1  = GND
  G1  = FM_LED_PWRGD_PVDDCR_SOC_P0
  D2  = LED_PWRGD_PVDDCR_CPU1_P0_D
  S2  = GND
  G2  = FM_LED_PWRGD_PVDDCR_CPU1_P0
  D1  = LED_PWRGD_PVDDCR_SOC_P0_D

(kicad_pcb
	(version 20260206)
	(generator "pcbnew")
	(generator_version "10.0")
	(general
		(thickness 1.6)
		(legacy_teardrops no)
	)
	(paper "A4")
	(title_block
		(title "04192023_DAF0TMB3IC0_F0TG_MB_C_brd_V02_OCP.brd")
		(comment 1 "Grand Teton / footprints 6561-6562 of 8354")
	)
	(layers
		(0 "F.Cu" signal "TOP")
		(4 "In1.Cu" signal "GND")
		(6 "In2.Cu" signal "IN1")
		(8 "In3.Cu" signal "GND1")
		(10 "In4.Cu" signal "IN2")
		(12 "In5.Cu" signal "GND2")
		(14 "In6.Cu" signal "IN3")
		(16 "In7.Cu" signal "GND3")
		(18 "In8.Cu" signal "VCC")
		(20 "In9.Cu" signal "VCC1")
		(22 "In10.Cu" signal "GND4")
		(24 "In11.Cu" signal "IN4")
		(26 "In12.Cu" signal "GND5")
		(28 "In13.Cu" signal "IN5")
		(30 "In14.Cu" signal "GND6")
		(32 "In15.Cu" signal "IN6")
		(34 "In16.Cu" signal "GND7")
		(2 "B.Cu" signal "BOTTOM")
		(9 "F.Adhes" user "F.Adhesive")
		(11 "B.Adhes" user "B.Adhesive")
		(13 "F.Paste" user "Package Geometry/Pastemask Top")
		(15 "B.Paste" user "Package Geometry/Pastemask Bottom")
		(5 "F.SilkS" user "Ref Des/Silkscreen Top")
		(7 "B.SilkS" user "Ref Des/Silkscreen Bottom")
		(1 "F.Mask" user "Board Geometry/Soldermask Top")
		(3 "B.Mask" user "Board Geometry/Soldermask Bottom")
		(17 "Dwgs.User" user "User.Drawings")
		(19 "Cmts.User" user "User.Comments")
		(21 "Eco1.User" user "User.Eco1")
		(23 "Eco2.User" user "User.Eco2")
		(25 "Edge.Cuts" user "Board Geometry/Outline")
		(27 "Margin" user)
		(31 "F.CrtYd" user "Package Geometry/Place Bound Top")
		(29 "B.CrtYd" user "Package Geometry/Place Bound Bottom")
		(35 "F.Fab" user "Ref Des/Assembly Top")
		(33 "B.Fab" user "Ref Des/Assembly Bottom")
	)
	(footprint ""
		(layer "B.Cu")
		(at 155.364434 -199.234552 -90)
		(property "Reference" "C231"
			(at 0 0 90)
			(layer "B.SilkS")
			(hide yes)
			(effects
				(font
					(size 1.27 1.27)
				)
				(justify mirror)
			)
		)
		(property "Value" ""
			(at 0 0 90)
			(layer "B.Fab")
			(effects
				(font
					(size 1.27 1.27)
				)
				(justify mirror)
			)
		)
		(duplicate_pad_numbers_are_jumpers no)
		(fp_line
			(start -0.7874 0.4064)
			(end 0.7874 0.4064)
			(stroke
				(width 0.1524)
				(type default)
			)
			(layer "B.SilkS")
		)
		(fp_line
			(start 0.7874 0.4064)
			(end 0.7874 -0.4064)
			(stroke
				(width 0.1524)
				(type default)
			)
			(layer "B.SilkS")
		)
		(fp_line
			(start -0.7874 -0.4064)
			(end -0.7874 0.4064)
			(stroke
				(width 0.1524)
				(type default)
			)
			(layer "B.SilkS")
		)
		(fp_line
			(start 0.7874 -0.4064)
			(end -0.7874 -0.4064)
			(stroke
				(width 0.1524)
				(type default)
			)
			(layer "B.SilkS")
		)
		(fp_line
			(start -0.67945 0.3048)
			(end -0.120396 0.3048)
			(stroke
				(width 0.1)
				(type default)
			)
			(layer "B.Fab")
		)
		(fp_line
			(start -0.120396 0.3048)
			(end -0.120396 0.2794)
			(stroke
				(width 0.1)
				(type default)
			)
			(layer "B.Fab")
		)
		(fp_line
			(start 0.12065 0.3048)
			(end 0.67945 0.3048)
			(stroke
				(width 0.1)
				(type default)
			)
			(layer "B.Fab")
		)
		(fp_line
			(start 0.67945 0.3048)
			(end 0.67945 -0.305054)
			(stroke
				(width 0.1)
				(type default)
			)
			(layer "B.Fab")
		)
		(fp_line
			(start -0.120396 0.2794)
			(end 0.12065 0.2794)
			(stroke
				(width 0.1)
				(type default)
			)
			(layer "B.Fab")
		)
		(fp_line
			(start 0.12065 0.2794)
			(end 0.12065 0.3048)
			(stroke
				(width 0.1)
				(type default)
			)
			(layer "B.Fab")
		)
		(fp_line
			(start -0.12065 -0.2794)
			(end -0.12065 -0.3048)
			(stroke
				(width 0.1)
				(type default)
			)
			(layer "B.Fab")
		)
		(fp_line
			(start 0.12065 -0.2794)
			(end -0.12065 -0.2794)
			(stroke
				(width 0.1)
				(type default)
			)
			(layer "B.Fab")
		)
		(fp_line
			(start -0.67945 -0.3048)
			(end -0.67945 0.3048)
			(stroke
				(width 0.1)
				(type default)
			)
			(layer "B.Fab")
		)
		(fp_line
			(start -0.12065 -0.3048)
			(end -0.67945 -0.3048)
			(stroke
				(width 0.1)
				(type default)
			)
			(layer "B.Fab")
		)
		(fp_line
			(start 0.12065 -0.305054)
			(end 0.12065 -0.2794)
			(stroke
				(width 0.1)
				(type default)
			)
			(layer "B.Fab")
		)
		(fp_line
			(start 0.67945 -0.305054)
			(end 0.12065 -0.305054)
			(stroke
				(width 0.1)
				(type default)
			)
			(layer "B.Fab")
		)
		(pad "1" smd circle
			(at 0.40005 0 90)
			(size 0 0)
			(layers "B.Cu" "B.Mask" "B.Paste")
			(net "JTAG_CPU1_TDI")
		)
		(pad "2" smd circle
			(at -0.40005 0 90)
			(size 0 0)
			(layers "B.Cu" "B.Mask" "B.Paste")
			(net "GND")
		)
	)
	(footprint ""
		(layer "B.Cu")
		(at 328.400664 -73.534778)
		(property "Reference" "Q80"
			(at 0.95885 -1.724152 0)
			(unlocked yes)
			(layer "B.SilkS")
			(effects
				(font
					(size 0.7874 0.5842)
					(thickness 0.1524)
				)
				(justify left mirror)
			)
		)
		(property "Value" ""
			(at 0 0 0)
			(layer "B.Fab")
			(effects
				(font
					(size 1.27 1.27)
				)
				(justify mirror)
			)
		)
		(duplicate_pad_numbers_are_jumpers no)
		(fp_line
			(start -1.332738 -1.100074)
			(end -1.332738 1.100074)
			(stroke
				(width 0.1524)
				(type default)
			)
			(layer "B.SilkS")
		)
		(fp_line
			(start -1.332738 1.100074)
			(end 1.332738 1.100074)
			(stroke
				(width 0.1524)
				(type default)
			)
			(layer "B.SilkS")
		)
		(fp_line
			(start -0.4826 -1.100074)
			(end -1.332738 -1.100074)
			(stroke
				(width 0.1524)
				(type default)
			)
			(layer "B.SilkS")
		)
		(fp_line
			(start 0 -0.541274)
			(end -0.4826 -1.100074)
			(stroke
				(width 0.1524)
				(type default)
			)
			(layer "B.SilkS")
		)
		(fp_line
			(start 0.4826 -1.100074)
			(end 0 -0.541274)
			(stroke
				(width 0.1524)
				(type default)
			)
			(layer "B.SilkS")
		)
		(fp_line
			(start 1.332738 -1.100074)
			(end 0.4826 -1.100074)
			(stroke
				(width 0.1524)
				(type default)
			)
			(layer "B.SilkS")
		)
		(fp_line
			(start 1.332738 1.100074)
			(end 1.332738 -1.100074)
			(stroke
				(width 0.1524)
				(type default)
			)
			(layer "B.SilkS")
		)
		(fp_poly
			(pts
				(xy 1.367536 -0.649986) (xy 2.069592 -1.001014) (xy 2.069592 -0.298958)
			)
			(stroke
				(width 0)
				(type default)
			)
			(fill yes)
			(layer "B.SilkS")
		)
		(fp_line
			(start -0.674878 -1.100074)
			(end -0.674878 1.100074)
			(stroke
				(width 0.1)
				(type default)
			)
			(layer "B.Fab")
		)
		(fp_line
			(start -0.674878 1.100074)
			(end 0.674878 1.100074)
			(stroke
				(width 0.1)
				(type default)
			)
			(layer "B.Fab")
		)
		(fp_line
			(start 0.674878 -1.100074)
			(end -0.674878 -1.100074)
			(stroke
				(width 0.1)
				(type default)
			)
			(layer "B.Fab")
		)
		(fp_line
			(start 0.674878 1.100074)
			(end 0.674878 -1.100074)
			(stroke
				(width 0.1)
				(type default)
			)
			(layer "B.Fab")
		)
		(fp_poly
			(pts
				(xy 2.2352 -0.298958) (xy 2.2352 -1.001014) (xy 1.533144 -0.649986)
			)
			(stroke
				(width 0)
				(type default)
			)
			(fill yes)
			(layer "B.Fab")
		)
		(pad "1" smd rect
			(at 0.94996 -0.649986 90)
			(size 0.4318 0.508)
			(layers "B.Cu" "B.Mask" "B.Paste")
			(net "GND")
		)
		(pad "2" smd rect
			(at 0.94996 0 90)
			(size 0.4318 0.508)
			(layers "B.Cu" "B.Mask" "B.Paste")
			(net "FM_LED_PWRGD_PVDDCR_SOC_P0")
		)
		(pad "3" smd rect
			(at 0.94996 0.649986 90)
			(size 0.4318 0.508)
			(layers "B.Cu" "B.Mask" "B.Paste")
			(net "LED_PWRGD_PVDDCR_CPU1_P0_D")
		)
		(pad "4" smd rect
			(at -0.94996 0.649986 90)
			(size 0.4318 0.508)
			(layers "B.Cu" "B.Mask" "B.Paste")
			(net "GND")
		)
		(pad "5" smd rect
			(at -0.94996 0 90)
			(size 0.4318 0.508)
			(layers "B.Cu" "B.Mask" "B.Paste")
			(net "FM_LED_PWRGD_PVDDCR_CPU1_P0")
		)
		(pad "6" smd rect
			(at -0.94996 -0.649986 90)
			(size 0.4318 0.508)
			(layers "B.Cu" "B.Mask" "B.Paste")
			(net "LED_PWRGD_PVDDCR_SOC_P0_D")
		)
	)
)
